(kicad_pcb
	(version 20260206)
	(generator "pcbnew")
	(generator_version "10.0")
	(general
		(thickness 1.6)
		(legacy_teardrops no)
	)
	(paper "A4")
	(title_block
		(title "04192023_DAF0TMB3IC0_F0TG_MB_C_brd_V02_OCP.brd")
		(comment 1 "Grand Teton / footprint 3102 of 8354 (U6011), pads 337-354 of 354")
	)
	(layers
		(0 "F.Cu" signal "TOP")
		(4 "In1.Cu" signal "GND")
		(6 "In2.Cu" signal "IN1")
		(8 "In3.Cu" signal "GND1")
		(10 "In4.Cu" signal "IN2")
		(12 "In5.Cu" signal "GND2")
		(14 "In6.Cu" signal "IN3")
		(16 "In7.Cu" signal "GND3")
		(18 "In8.Cu" signal "VCC")
		(20 "In9.Cu" signal "VCC1")
		(22 "In10.Cu" signal "GND4")
		(24 "In11.Cu" signal "IN4")
		(26 "In12.Cu" signal "GND5")
		(28 "In13.Cu" signal "IN5")
		(30 "In14.Cu" signal "GND6")
		(32 "In15.Cu" signal "IN6")
		(34 "In16.Cu" signal "GND7")
		(2 "B.Cu" signal "BOTTOM")
		(9 "F.Adhes" user "F.Adhesive")
		(11 "B.Adhes" user "B.Adhesive")
		(13 "F.Paste" user "Package Geometry/Pastemask Top")
		(15 "B.Paste" user "Package Geometry/Pastemask Bottom")
		(5 "F.SilkS" user "Ref Des/Silkscreen Top")
		(7 "B.SilkS" user "Ref Des/Silkscreen Bottom")
		(1 "F.Mask" user "Board Geometry/Soldermask Top")
		(3 "B.Mask" user "Board Geometry/Soldermask Bottom")
		(17 "Dwgs.User" user "User.Drawings")
		(19 "Cmts.User" user "User.Comments")
		(21 "Eco1.User" user "User.Eco1")
		(23 "Eco2.User" user "User.Eco2")
		(25 "Edge.Cuts" user "Board Geometry/Outline")
		(27 "Margin" user)
		(31 "F.CrtYd" user "Package Geometry/Place Bound Top")
		(29 "B.CrtYd" user "Package Geometry/Place Bound Bottom")
		(35 "F.Fab" user "Ref Des/Assembly Top")
		(33 "B.Fab" user "Ref Des/Assembly Bottom")
	)
	(footprint ""
		(layer "F.Cu")
		(at 344.9955 -395.724634)
		(property "Reference" "U6011"
			(at -8.11784 -7.526528 0)
			(unlocked yes)
			(layer "F.SilkS")
			(effects
				(font
					(size 0.7874 0.5842)
					(thickness 0.1524)
				)
				(justify left)
			)
		)
		(property "Value" ""
			(at 0 0 0)
			(layer "F.Fab")
			(effects
				(font
					(size 1.27 1.27)
				)
			)
		)
		(duplicate_pad_numbers_are_jumpers no)
		(pad "P10" smd circle
			(at 8.802624 -1.431798)
			(size 0.381 0.381)
			(layers "F.Cu" "F.Mask" "F.Paste")
			(net "P5E_CPU0_P1_TX_BUF_DN<15>")
		)
		(pad "P29" smd circle
			(at 8.802624 2.032254)
			(size 0.381 0.381)
			(layers "F.Cu" "F.Mask" "F.Paste")
			(net "P5E_CPU0_P1_RX_DN<15>")
		)
		(pad "R1" smd oval
			(at 8.64997 -3.938524)
			(size 0.254 0.3302)
			(layers "F.Cu" "F.Mask" "F.Paste")
			(net "P5E_CPU0_P1_RX_BUF_DP<15>")
		)
		(pad "R35" smd oval
			(at 8.64997 3.940048)
			(size 0.254 0.3302)
			(layers "F.Cu" "F.Mask" "F.Paste")
			(net "P5E_CPU0_P1_TX_C_DP<15>")
		)
		(pad "T4" smd circle
			(at 8.402574 -2.817368)
			(size 0.381 0.381)
			(layers "F.Cu" "F.Mask" "F.Paste")
			(net "GND")
		)
		(pad "T13" smd circle
			(at 8.402574 -0.79629)
			(size 0.3048 0.3048)
			(layers "F.Cu" "F.Mask" "F.Paste")
			(net "GND")
		)
		(pad "T17" smd circle
			(at 8.402574 -0.296164)
			(size 0.3048 0.3048)
			(layers "F.Cu" "F.Mask" "F.Paste")
			(net "P0V9_CPU0_RT1_2A")
		)
		(pad "T20" smd circle
			(at 8.402574 0.203708)
			(size 0.3048 0.3048)
			(layers "F.Cu" "F.Mask" "F.Paste")
			(net "P0V9_CPU0_RT1_2A")
		)
		(pad "T22" smd circle
			(at 8.402574 0.703834)
			(size 0.3048 0.3048)
			(layers "F.Cu" "F.Mask" "F.Paste")
			(net "GND")
		)
		(pad "T32" smd circle
			(at 8.402574 2.724912)
			(size 0.381 0.381)
			(layers "F.Cu" "F.Mask" "F.Paste")
			(net "GND")
		)
		(pad "U2" smd circle
			(at 8.349996 -3.41884)
			(size 0.3048 0.3048)
			(layers "F.Cu" "F.Mask" "F.Paste")
			(net "GND")
		)
		(pad "U34" smd circle
			(at 8.349996 3.420364)
			(size 0.3048 0.3048)
			(layers "F.Cu" "F.Mask" "F.Paste")
			(net "GND")
		)
		(pad "V1" smd oval
			(at 8.050022 -3.938524)
			(size 0.254 0.3302)
			(layers "F.Cu" "F.Mask" "F.Paste")
			(net "GND")
		)
		(pad "V35" smd oval
			(at 8.050022 3.940048)
			(size 0.254 0.3302)
			(layers "F.Cu" "F.Mask" "F.Paste")
			(net "GND")
		)
		(pad "W7" smd circle
			(at 8.002524 -2.12471)
			(size 0.381 0.381)
			(layers "F.Cu" "F.Mask" "F.Paste")
			(net "P5E_CPU0_P1_TX_BUF_DP<14>")
		)
		(pad "W26" smd circle
			(at 8.002524 1.339342)
			(size 0.381 0.381)
			(layers "F.Cu" "F.Mask" "F.Paste")
			(net "P5E_CPU0_P1_RX_DP<14>")
		)
		(pad "Y2" smd circle
			(at 7.750048 -3.41884)
			(size 0.3048 0.3048)
			(layers "F.Cu" "F.Mask" "F.Paste")
			(net "P5E_CPU0_P1_RX_BUF_DN<14>")
		)
		(pad "Y34" smd circle
			(at 7.750048 3.420364)
			(size 0.3048 0.3048)
			(layers "F.Cu" "F.Mask" "F.Paste")
			(net "P5E_CPU0_P1_TX_C_DP<14>")
		)
	)
)
